# BASEBOARD_FAB2 (Tioga Pass) — schematic netlist excerpt (pin names and nets, part order shuffled) for the footprints in the layout excerpt that follows; sources: Cadence DE-HDL packaged netlist, KiCad conversion of Wiwynn_Tioga_Pass_MB.brd

C30W9  SC22U16V5MX-4-GP  20%  pkg SMD-BCG5  page 253 : \1\ = P5V_STBY_USBC ; \2\ = GND
R7P7  RES  42.2 1.0% EMPTY  pkg 0402  page 103 : A = CLK_100M_CPU1_RC_REFCLK0_DN ; B = GND
C9N10  CAP  0.22UF 16V 10% X7R  pkg 0402  page 182 : A = P3E_CPU1_PE3_MP_C_TXP<14> ; B = P3E_CPU1_PE3_MP_TXP<14>

(kicad_pcb
	(version 20260206)
	(generator "pcbnew")
	(generator_version "10.0")
	(general
		(thickness 1.6)
		(legacy_teardrops no)
	)
	(paper "A4")
	(title_block
		(title "Wiwynn_Tioga_Pass_MB.brd")
		(comment 1 "Tioga Pass / footprints 2861-2863 of 4770")
	)
	(layers
		(0 "F.Cu" signal "TOP")
		(4 "In1.Cu" signal "L2GND")
		(6 "In2.Cu" signal "L3")
		(8 "In3.Cu" signal "L4GND")
		(10 "In4.Cu" signal "L5")
		(12 "In5.Cu" signal "L6GND")
		(14 "In6.Cu" signal "L7VCC")
		(16 "In7.Cu" signal "L8VCC")
		(18 "In8.Cu" signal "L9GND")
		(20 "In9.Cu" signal "L10")
		(22 "In10.Cu" signal "L11GND")
		(24 "In11.Cu" signal "L12")
		(26 "In12.Cu" signal "L13GND")
		(2 "B.Cu" signal "BOTTOM")
		(9 "F.Adhes" user "F.Adhesive")
		(11 "B.Adhes" user "B.Adhesive")
		(13 "F.Paste" user "Package Geometry/Pastemask Top")
		(15 "B.Paste" user "Package Geometry/Pastemask Bottom")
		(5 "F.SilkS" user "Ref Des/Silkscreen Top")
		(7 "B.SilkS" user "Ref Des/Silkscreen Bottom")
		(1 "F.Mask" user "Board Geometry/Soldermask Top")
		(3 "B.Mask" user "Board Geometry/Soldermask Bottom")
		(17 "Dwgs.User" user "User.Drawings")
		(19 "Cmts.User" user "User.Comments")
		(21 "Eco1.User" user "User.Eco1")
		(23 "Eco2.User" user "User.Eco2")
		(25 "Edge.Cuts" user "Board Geometry/Outline")
		(27 "Margin" user)
		(31 "F.CrtYd" user "Package Geometry/Place Bound Top")
		(29 "B.CrtYd" user "Package Geometry/Place Bound Bottom")
		(35 "F.Fab" user "Ref Des/Assembly Top")
		(33 "B.Fab" user "Ref Des/Assembly Bottom")
	)
	(footprint ""
		(layer "B.Cu")
		(at 486.300526 -55.853584)
		(property "Reference" "C30W9"
			(at 0 0 0)
			(layer "B.SilkS")
			(hide yes)
			(effects
				(font
					(size 1.27 1.27)
				)
				(justify mirror)
			)
		)
		(property "Value" "*"
			(at 0.0762 -6.2357 0)
			(unlocked yes)
			(layer "B.Fab")
			(hide yes)
			(effects
				(font
					(size 1.27 1.016)
					(thickness 0.1524)
				)
				(justify mirror)
			)
		)
		(property "Device Type" "SC22U16V5MX-4-GP_SMD-BCG5-SC22A"
			(at 0.0762 -8.2677 0)
			(unlocked yes)
			(layer "B.Fab")
			(hide yes)
			(effects
				(font
					(size 1.27 1.016)
					(thickness 0.1524)
				)
				(justify mirror)
			)
		)
		(duplicate_pad_numbers_are_jumpers no)
		(fp_line
			(start -0.635 0)
			(end 0.635 0)
			(stroke
				(width 0.508)
				(type default)
			)
			(layer "B.SilkS")
		)
		(fp_rect
			(start 0.9652 1.778)
			(end -0.9652 -1.778)
			(stroke
				(width 0)
				(type default)
			)
			(fill no)
			(layer "B.CrtYd")
		)
		(fp_poly
			(pts
				(xy 0.9652 -1.778) (xy -0.9652 -1.778) (xy -0.9652 1.778) (xy 0.9652 1.778)
			)
			(stroke
				(width 0)
				(type default)
			)
			(fill no)
			(layer "B.Fab")
		)
		(pad "1" smd rect
			(at 0 -0.9652 180)
			(size 1.397 1.143)
			(layers "B.Cu" "B.Mask" "B.Paste")
			(net "P5V_STBY_USBC")
		)
		(pad "2" smd rect
			(at 0 0.9652 180)
			(size 1.397 1.143)
			(layers "B.Cu" "B.Mask" "B.Paste")
			(net "GND")
		)
	)
	(footprint ""
		(layer "B.Cu")
		(at 162.7886 -79.248 90)
		(property "Reference" "R7P7"
			(at 0 0 90)
			(layer "B.SilkS")
			(hide yes)
			(effects
				(font
					(size 1.27 1.27)
				)
				(justify mirror)
			)
		)
		(property "Value" ""
			(at 0 0 90)
			(layer "B.Fab")
			(effects
				(font
					(size 1.27 1.27)
				)
				(justify mirror)
			)
		)
		(duplicate_pad_numbers_are_jumpers no)
		(fp_poly
			(pts
				(xy 0.2794 -0.1016) (xy -0.2794 -0.1016) (xy -0.2794 0.9906) (xy 0.2794 0.9906)
			)
			(stroke
				(width 0)
				(type default)
			)
			(fill no)
			(layer "B.CrtYd")
		)
		(fp_line
			(start 0.2794 -0.1016)
			(end 0.2794 0.9906)
			(stroke
				(width 0.1)
				(type default)
			)
			(layer "B.Fab")
		)
		(fp_line
			(start -0.2794 -0.1016)
			(end 0.2794 -0.1016)
			(stroke
				(width 0.1)
				(type default)
			)
			(layer "B.Fab")
		)
		(fp_line
			(start 0.2794 0.9906)
			(end -0.2794 0.9906)
			(stroke
				(width 0.1)
				(type default)
			)
			(layer "B.Fab")
		)
		(fp_line
			(start -0.2794 0.9906)
			(end -0.2794 -0.1016)
			(stroke
				(width 0.1)
				(type default)
			)
			(layer "B.Fab")
		)
		(pad "1" smd rect
			(at 0 0 270)
			(size 0.508 0.508)
			(layers "B.Cu" "B.Mask" "B.Paste")
			(net "CLK_100M_CPU1_RC_REFCLK0_DN")
		)
		(pad "2" smd rect
			(at 0 0.889 270)
			(size 0.508 0.508)
			(layers "B.Cu" "B.Mask" "B.Paste")
			(net "GND")
		)
		(zone
			(layer "B.Cu")
			(hatch none 0.5)
			(connect_pads
				(clearance 0)
			)
			(min_thickness 0.25)
			(keepout
				(tracks allowed)
				(vias not_allowed)
				(pads allowed)
				(copperpour not_allowed)
				(footprints allowed)
			)
			(placement
				(enabled no)
				(sheetname "")
			)
			(fill
				(thermal_gap 0.5)
				(thermal_bridge_width 0.5)
				(island_removal_mode 0)
			)
			(polygon
				(pts
					(xy 163.0426 -79.502) (xy 163.0426 -78.994) (xy 163.4236 -78.994) (xy 163.4236 -79.502)
				)
			)
		)
		(zone
			(layer "B.Cu")
			(hatch none 0.5)
			(connect_pads
				(clearance 0)
			)
			(min_thickness 0.25)
			(keepout
				(tracks not_allowed)
				(vias allowed)
				(pads allowed)
				(copperpour not_allowed)
				(footprints allowed)
			)
			(placement
				(enabled no)
				(sheetname "")
			)
			(fill
				(thermal_gap 0.5)
				(thermal_bridge_width 0.5)
				(island_removal_mode 0)
			)
			(polygon
				(pts
					(xy 163.4236 -79.502) (xy 163.4236 -78.994) (xy 163.0426 -78.994) (xy 163.0426 -79.502)
				)
			)
		)
	)
	(footprint ""
		(layer "B.Cu")
		(at 12.40282 -101.57968 90)
		(property "Reference" "C9N10"
			(at 0 0 90)
			(layer "B.SilkS")
			(hide yes)
			(effects
				(font
					(size 1.27 1.27)
				)
				(justify mirror)
			)
		)
		(property "Value" ""
			(at 0 0 90)
			(layer "B.Fab")
			(effects
				(font
					(size 1.27 1.27)
				)
				(justify mirror)
			)
		)
		(duplicate_pad_numbers_are_jumpers no)
		(fp_poly
			(pts
				(xy -0.3048 -0.1016) (xy -0.3048 0.9906) (xy 0.3048 0.9906) (xy 0.3048 -0.1016)
			)
			(stroke
				(width 0)
				(type default)
			)
			(fill no)
			(layer "B.CrtYd")
		)
		(fp_line
			(start 0.3048 -0.1016)
			(end 0.3048 0.9906)
			(stroke
				(width 0.1)
				(type default)
			)
			(layer "B.Fab")
		)
		(fp_line
			(start -0.3048 -0.1016)
			(end 0.3048 -0.1016)
			(stroke
				(width 0.1)
				(type default)
			)
			(layer "B.Fab")
		)
		(fp_line
			(start 0.3048 0.9906)
			(end -0.3048 0.9906)
			(stroke
				(width 0.1)
				(type default)
			)
			(layer "B.Fab")
		)
		(fp_line
			(start -0.3048 0.9906)
			(end -0.3048 -0.1016)
			(stroke
				(width 0.1)
				(type default)
			)
			(layer "B.Fab")
		)
		(pad "1" smd rect
			(at 0 0 270)
			(size 0.508 0.508)
			(layers "B.Cu" "B.Mask" "B.Paste")
			(net "P3E_CPU1_PE3_MP_C_TXP<14>")
		)
		(pad "2" smd rect
			(at 0 0.889 270)
			(size 0.508 0.508)
			(layers "B.Cu" "B.Mask" "B.Paste")
			(net "P3E_CPU1_PE3_MP_TXP<14>")
		)
		(zone
			(layer "B.Cu")
			(hatch none 0.5)
			(connect_pads
				(clearance 0)
			)
			(min_thickness 0.25)
			(keepout
				(tracks allowed)
				(vias not_allowed)
				(pads allowed)
				(copperpour not_allowed)
				(footprints allowed)
			)
			(placement
				(enabled no)
				(sheetname "")
			)
			(fill
				(thermal_gap 0.5)
				(thermal_bridge_width 0.5)
				(island_removal_mode 0)
			)
			(polygon
				(pts
					(xy 12.65682 -101.83368) (xy 12.65682 -101.32568) (xy 13.03782 -101.32568) (xy 13.03782 -101.83368)
				)
			)
		)
		(zone
			(layer "B.Cu")
			(hatch none 0.5)
			(connect_pads
				(clearance 0)
			)
			(min_thickness 0.25)
			(keepout
				(tracks not_allowed)
				(vias allowed)
				(pads allowed)
				(copperpour not_allowed)
				(footprints allowed)
			)
			(placement
				(enabled no)
				(sheetname "")
			)
			(fill
				(thermal_gap 0.5)
				(thermal_bridge_width 0.5)
				(island_removal_mode 0)
			)
			(polygon
				(pts
					(xy 13.03782 -101.83368) (xy 13.03782 -101.32568) (xy 12.65682 -101.32568) (xy 12.65682 -101.83368)
				)
			)
		)
	)
)
